# T6G (Grand Teton) — schematic netlist excerpt (pin names and nets, part order shuffled) for the footprints in the layout excerpt that follows; sources: Cadence DE-HDL packaged netlist, KiCad conversion of 04192023_DAF0TMB3IC0_F0TG_MB_C_brd_V02_OCP.brd

PR113  Q_RES  40.2K 1% CHIP  pkg 0402LF  page 207 : A = P5V_AUX ; B = PVDD11_S3_P0_VMON
R4304  Q_RES  0 5% CHIP  pkg 0402LF  page 28 : A = CLK_100M_CPU0_CLK12_R_DN ; B = CLK_100M_CPU0_CLK12_DN

(kicad_pcb
	(version 20260206)
	(generator "pcbnew")
	(generator_version "10.0")
	(general
		(thickness 1.6)
		(legacy_teardrops no)
	)
	(paper "A4")
	(title_block
		(title "04192023_DAF0TMB3IC0_F0TG_MB_C_brd_V02_OCP.brd")
		(comment 1 "Grand Teton / footprints 7799-7800 of 8354")
	)
	(layers
		(0 "F.Cu" signal "TOP")
		(4 "In1.Cu" signal "GND")
		(6 "In2.Cu" signal "IN1")
		(8 "In3.Cu" signal "GND1")
		(10 "In4.Cu" signal "IN2")
		(12 "In5.Cu" signal "GND2")
		(14 "In6.Cu" signal "IN3")
		(16 "In7.Cu" signal "GND3")
		(18 "In8.Cu" signal "VCC")
		(20 "In9.Cu" signal "VCC1")
		(22 "In10.Cu" signal "GND4")
		(24 "In11.Cu" signal "IN4")
		(26 "In12.Cu" signal "GND5")
		(28 "In13.Cu" signal "IN5")
		(30 "In14.Cu" signal "GND6")
		(32 "In15.Cu" signal "IN6")
		(34 "In16.Cu" signal "GND7")
		(2 "B.Cu" signal "BOTTOM")
		(9 "F.Adhes" user "F.Adhesive")
		(11 "B.Adhes" user "B.Adhesive")
		(13 "F.Paste" user "Package Geometry/Pastemask Top")
		(15 "B.Paste" user "Package Geometry/Pastemask Bottom")
		(5 "F.SilkS" user "Ref Des/Silkscreen Top")
		(7 "B.SilkS" user "Ref Des/Silkscreen Bottom")
		(1 "F.Mask" user "Board Geometry/Soldermask Top")
		(3 "B.Mask" user "Board Geometry/Soldermask Bottom")
		(17 "Dwgs.User" user "User.Drawings")
		(19 "Cmts.User" user "User.Comments")
		(21 "Eco1.User" user "User.Eco1")
		(23 "Eco2.User" user "User.Eco2")
		(25 "Edge.Cuts" user "Board Geometry/Outline")
		(27 "Margin" user)
		(31 "F.CrtYd" user "Package Geometry/Place Bound Top")
		(29 "B.CrtYd" user "Package Geometry/Place Bound Bottom")
		(35 "F.Fab" user "Ref Des/Assembly Top")
		(33 "B.Fab" user "Ref Des/Assembly Bottom")
	)
	(footprint ""
		(layer "B.Cu")
		(at 424.646598 -362.378244)
		(property "Reference" "PR113"
			(at 0 0 0)
			(layer "B.SilkS")
			(hide yes)
			(effects
				(font
					(size 1.27 1.27)
				)
				(justify mirror)
			)
		)
		(property "Value" ""
			(at 0 0 0)
			(layer "B.Fab")
			(effects
				(font
					(size 1.27 1.27)
				)
				(justify mirror)
			)
		)
		(duplicate_pad_numbers_are_jumpers no)
		(fp_line
			(start -0.7874 -0.4064)
			(end -0.7874 0.4064)
			(stroke
				(width 0.1524)
				(type default)
			)
			(layer "B.SilkS")
		)
		(fp_line
			(start -0.7874 0.4064)
			(end 0.7874 0.4064)
			(stroke
				(width 0.1524)
				(type default)
			)
			(layer "B.SilkS")
		)
		(fp_line
			(start 0.7874 -0.4064)
			(end -0.7874 -0.4064)
			(stroke
				(width 0.1524)
				(type default)
			)
			(layer "B.SilkS")
		)
		(fp_line
			(start 0.7874 0.4064)
			(end 0.7874 -0.4064)
			(stroke
				(width 0.1524)
				(type default)
			)
			(layer "B.SilkS")
		)
		(fp_line
			(start -0.67945 -0.3048)
			(end -0.67945 0.3048)
			(stroke
				(width 0.1)
				(type default)
			)
			(layer "B.Fab")
		)
		(fp_line
			(start -0.67945 0.3048)
			(end -0.120396 0.3048)
			(stroke
				(width 0.1)
				(type default)
			)
			(layer "B.Fab")
		)
		(fp_line
			(start -0.12065 -0.3048)
			(end -0.67945 -0.3048)
			(stroke
				(width 0.1)
				(type default)
			)
			(layer "B.Fab")
		)
		(fp_line
			(start -0.12065 -0.2794)
			(end -0.12065 -0.3048)
			(stroke
				(width 0.1)
				(type default)
			)
			(layer "B.Fab")
		)
		(fp_line
			(start -0.120396 0.2794)
			(end 0.12065 0.2794)
			(stroke
				(width 0.1)
				(type default)
			)
			(layer "B.Fab")
		)
		(fp_line
			(start -0.120396 0.3048)
			(end -0.120396 0.2794)
			(stroke
				(width 0.1)
				(type default)
			)
			(layer "B.Fab")
		)
		(fp_line
			(start 0.12065 -0.305054)
			(end 0.12065 -0.2794)
			(stroke
				(width 0.1)
				(type default)
			)
			(layer "B.Fab")
		)
		(fp_line
			(start 0.12065 -0.2794)
			(end -0.12065 -0.2794)
			(stroke
				(width 0.1)
				(type default)
			)
			(layer "B.Fab")
		)
		(fp_line
			(start 0.12065 0.2794)
			(end 0.12065 0.3048)
			(stroke
				(width 0.1)
				(type default)
			)
			(layer "B.Fab")
		)
		(fp_line
			(start 0.12065 0.3048)
			(end 0.67945 0.3048)
			(stroke
				(width 0.1)
				(type default)
			)
			(layer "B.Fab")
		)
		(fp_line
			(start 0.67945 -0.305054)
			(end 0.12065 -0.305054)
			(stroke
				(width 0.1)
				(type default)
			)
			(layer "B.Fab")
		)
		(fp_line
			(start 0.67945 0.3048)
			(end 0.67945 -0.305054)
			(stroke
				(width 0.1)
				(type default)
			)
			(layer "B.Fab")
		)
		(pad "1" smd circle
			(at 0.40005 0 180)
			(size 0 0)
			(layers "B.Cu" "B.Mask" "B.Paste")
			(net "P5V_AUX")
		)
		(pad "2" smd circle
			(at -0.40005 0 180)
			(size 0 0)
			(layers "B.Cu" "B.Mask" "B.Paste")
			(net "PVDD11_S3_P0_VMON")
		)
	)
	(footprint ""
		(layer "B.Cu")
		(at 342.498934 -301.911258 -90)
		(property "Reference" "R4304"
			(at 0 0 90)
			(layer "B.SilkS")
			(hide yes)
			(effects
				(font
					(size 1.27 1.27)
				)
				(justify mirror)
			)
		)
		(property "Value" ""
			(at 0 0 90)
			(layer "B.Fab")
			(effects
				(font
					(size 1.27 1.27)
				)
				(justify mirror)
			)
		)
		(duplicate_pad_numbers_are_jumpers no)
		(fp_line
			(start -0.7874 0.4064)
			(end 0.7874 0.4064)
			(stroke
				(width 0.1524)
				(type default)
			)
			(layer "B.SilkS")
		)
		(fp_line
			(start 0.7874 0.4064)
			(end 0.7874 0.056134)
			(stroke
				(width 0.1524)
				(type default)
			)
			(layer "B.SilkS")
		)
		(fp_line
			(start -0.7874 0.056134)
			(end -0.7874 0.4064)
			(stroke
				(width 0.1524)
				(type default)
			)
			(layer "B.SilkS")
		)
		(fp_line
			(start 0.311658 -0.4064)
			(end -0.374142 -0.4064)
			(stroke
				(width 0.1524)
				(type default)
			)
			(layer "B.SilkS")
		)
		(fp_line
			(start -0.67945 0.3048)
			(end -0.120396 0.3048)
			(stroke
				(width 0.1)
				(type default)
			)
			(layer "B.Fab")
		)
		(fp_line
			(start -0.120396 0.3048)
			(end -0.120396 0.2794)
			(stroke
				(width 0.1)
				(type default)
			)
			(layer "B.Fab")
		)
		(fp_line
			(start 0.12065 0.3048)
			(end 0.67945 0.3048)
			(stroke
				(width 0.1)
				(type default)
			)
			(layer "B.Fab")
		)
		(fp_line
			(start 0.67945 0.3048)
			(end 0.67945 -0.305054)
			(stroke
				(width 0.1)
				(type default)
			)
			(layer "B.Fab")
		)
		(fp_line
			(start -0.120396 0.2794)
			(end 0.12065 0.2794)
			(stroke
				(width 0.1)
				(type default)
			)
			(layer "B.Fab")
		)
		(fp_line
			(start 0.12065 0.2794)
			(end 0.12065 0.3048)
			(stroke
				(width 0.1)
				(type default)
			)
			(layer "B.Fab")
		)
		(fp_line
			(start -0.12065 -0.2794)
			(end -0.12065 -0.3048)
			(stroke
				(width 0.1)
				(type default)
			)
			(layer "B.Fab")
		)
		(fp_line
			(start 0.12065 -0.2794)
			(end -0.12065 -0.2794)
			(stroke
				(width 0.1)
				(type default)
			)
			(layer "B.Fab")
		)
		(fp_line
			(start -0.67945 -0.3048)
			(end -0.67945 0.3048)
			(stroke
				(width 0.1)
				(type default)
			)
			(layer "B.Fab")
		)
		(fp_line
			(start -0.12065 -0.3048)
			(end -0.67945 -0.3048)
			(stroke
				(width 0.1)
				(type default)
			)
			(layer "B.Fab")
		)
		(fp_line
			(start 0.12065 -0.305054)
			(end 0.12065 -0.2794)
			(stroke
				(width 0.1)
				(type default)
			)
			(layer "B.Fab")
		)
		(fp_line
			(start 0.67945 -0.305054)
			(end 0.12065 -0.305054)
			(stroke
				(width 0.1)
				(type default)
			)
			(layer "B.Fab")
		)
		(pad "1" smd circle
			(at 0.40005 0 90)
			(size 0 0)
			(layers "B.Cu" "B.Mask" "B.Paste")
			(net "CLK_100M_CPU0_CLK12_R_DN")
		)
		(pad "2" smd circle
			(at -0.40005 0 90)
			(size 0 0)
			(layers "B.Cu" "B.Mask" "B.Paste")
			(net "CLK_100M_CPU0_CLK12_DN")
		)
	)
)
